# T6G (Grand Teton) — schematic netlist excerpt (pin names and nets, part order shuffled) for the footprints in the layout excerpt that follows; sources: Cadence DE-HDL packaged netlist, KiCad conversion of 04192023_DAF0TMB3IC0_F0TG_MB_C_brd_V02_OCP.brd

C176  Q_CAP  0.1UF 25V 10% X7R  pkg 0402  page 108 : A = P3V3_AUX ; B = GND
C234  Q_CAP  0.001UF 50V 10% EMPTY  pkg C0402  page 54 : A = JTAG_CPU1_TMS ; B = GND
C987  Q_CAP  0.1UF 10V 10% X7S  pkg C0201  page 301 : A = P0V9_CPU0_RT2_2A ; B = GND

(kicad_pcb
	(version 20260206)
	(generator "pcbnew")
	(generator_version "10.0")
	(general
		(thickness 1.6)
		(legacy_teardrops no)
	)
	(paper "A4")
	(title_block
		(title "04192023_DAF0TMB3IC0_F0TG_MB_C_brd_V02_OCP.brd")
		(comment 1 "Grand Teton / footprints 5261-5263 of 8354")
	)
	(layers
		(0 "F.Cu" signal "TOP")
		(4 "In1.Cu" signal "GND")
		(6 "In2.Cu" signal "IN1")
		(8 "In3.Cu" signal "GND1")
		(10 "In4.Cu" signal "IN2")
		(12 "In5.Cu" signal "GND2")
		(14 "In6.Cu" signal "IN3")
		(16 "In7.Cu" signal "GND3")
		(18 "In8.Cu" signal "VCC")
		(20 "In9.Cu" signal "VCC1")
		(22 "In10.Cu" signal "GND4")
		(24 "In11.Cu" signal "IN4")
		(26 "In12.Cu" signal "GND5")
		(28 "In13.Cu" signal "IN5")
		(30 "In14.Cu" signal "GND6")
		(32 "In15.Cu" signal "IN6")
		(34 "In16.Cu" signal "GND7")
		(2 "B.Cu" signal "BOTTOM")
		(9 "F.Adhes" user "F.Adhesive")
		(11 "B.Adhes" user "B.Adhesive")
		(13 "F.Paste" user "Package Geometry/Pastemask Top")
		(15 "B.Paste" user "Package Geometry/Pastemask Bottom")
		(5 "F.SilkS" user "Ref Des/Silkscreen Top")
		(7 "B.SilkS" user "Ref Des/Silkscreen Bottom")
		(1 "F.Mask" user "Board Geometry/Soldermask Top")
		(3 "B.Mask" user "Board Geometry/Soldermask Bottom")
		(17 "Dwgs.User" user "User.Drawings")
		(19 "Cmts.User" user "User.Comments")
		(21 "Eco1.User" user "User.Eco1")
		(23 "Eco2.User" user "User.Eco2")
		(25 "Edge.Cuts" user "Board Geometry/Outline")
		(27 "Margin" user)
		(31 "F.CrtYd" user "Package Geometry/Place Bound Top")
		(29 "B.CrtYd" user "Package Geometry/Place Bound Bottom")
		(35 "F.Fab" user "Ref Des/Assembly Top")
		(33 "B.Fab" user "Ref Des/Assembly Bottom")
	)
	(footprint ""
		(layer "B.Cu")
		(at 147.261834 -203.679552 -90)
		(property "Reference" "C234"
			(at 0 0 90)
			(layer "B.SilkS")
			(hide yes)
			(effects
				(font
					(size 1.27 1.27)
				)
				(justify mirror)
			)
		)
		(property "Value" ""
			(at 0 0 90)
			(layer "B.Fab")
			(effects
				(font
					(size 1.27 1.27)
				)
				(justify mirror)
			)
		)
		(duplicate_pad_numbers_are_jumpers no)
		(fp_line
			(start -0.7874 0.4064)
			(end 0.7874 0.4064)
			(stroke
				(width 0.1524)
				(type default)
			)
			(layer "B.SilkS")
		)
		(fp_line
			(start 0.7874 0.4064)
			(end 0.7874 -0.4064)
			(stroke
				(width 0.1524)
				(type default)
			)
			(layer "B.SilkS")
		)
		(fp_line
			(start -0.7874 -0.4064)
			(end -0.7874 0.4064)
			(stroke
				(width 0.1524)
				(type default)
			)
			(layer "B.SilkS")
		)
		(fp_line
			(start 0.7874 -0.4064)
			(end -0.7874 -0.4064)
			(stroke
				(width 0.1524)
				(type default)
			)
			(layer "B.SilkS")
		)
		(fp_line
			(start -0.67945 0.3048)
			(end -0.120396 0.3048)
			(stroke
				(width 0.1)
				(type default)
			)
			(layer "B.Fab")
		)
		(fp_line
			(start -0.120396 0.3048)
			(end -0.120396 0.2794)
			(stroke
				(width 0.1)
				(type default)
			)
			(layer "B.Fab")
		)
		(fp_line
			(start 0.12065 0.3048)
			(end 0.67945 0.3048)
			(stroke
				(width 0.1)
				(type default)
			)
			(layer "B.Fab")
		)
		(fp_line
			(start 0.67945 0.3048)
			(end 0.67945 -0.305054)
			(stroke
				(width 0.1)
				(type default)
			)
			(layer "B.Fab")
		)
		(fp_line
			(start -0.120396 0.2794)
			(end 0.12065 0.2794)
			(stroke
				(width 0.1)
				(type default)
			)
			(layer "B.Fab")
		)
		(fp_line
			(start 0.12065 0.2794)
			(end 0.12065 0.3048)
			(stroke
				(width 0.1)
				(type default)
			)
			(layer "B.Fab")
		)
		(fp_line
			(start -0.12065 -0.2794)
			(end -0.12065 -0.3048)
			(stroke
				(width 0.1)
				(type default)
			)
			(layer "B.Fab")
		)
		(fp_line
			(start 0.12065 -0.2794)
			(end -0.12065 -0.2794)
			(stroke
				(width 0.1)
				(type default)
			)
			(layer "B.Fab")
		)
		(fp_line
			(start -0.67945 -0.3048)
			(end -0.67945 0.3048)
			(stroke
				(width 0.1)
				(type default)
			)
			(layer "B.Fab")
		)
		(fp_line
			(start -0.12065 -0.3048)
			(end -0.67945 -0.3048)
			(stroke
				(width 0.1)
				(type default)
			)
			(layer "B.Fab")
		)
		(fp_line
			(start 0.12065 -0.305054)
			(end 0.12065 -0.2794)
			(stroke
				(width 0.1)
				(type default)
			)
			(layer "B.Fab")
		)
		(fp_line
			(start 0.67945 -0.305054)
			(end 0.12065 -0.305054)
			(stroke
				(width 0.1)
				(type default)
			)
			(layer "B.Fab")
		)
		(pad "1" smd circle
			(at 0.40005 0 90)
			(size 0 0)
			(layers "B.Cu" "B.Mask" "B.Paste")
			(net "JTAG_CPU1_TMS")
		)
		(pad "2" smd circle
			(at -0.40005 0 90)
			(size 0 0)
			(layers "B.Cu" "B.Mask" "B.Paste")
			(net "GND")
		)
	)
	(footprint ""
		(layer "B.Cu")
		(at 421.090344 -392.684762 -90)
		(property "Reference" "C987"
			(at 0 0 90)
			(layer "B.SilkS")
			(hide yes)
			(effects
				(font
					(size 1.27 1.27)
				)
				(justify mirror)
			)
		)
		(property "Value" ""
			(at 0 0 90)
			(layer "B.Fab")
			(effects
				(font
					(size 1.27 1.27)
				)
				(justify mirror)
			)
		)
		(duplicate_pad_numbers_are_jumpers no)
		(fp_line
			(start -0.299974 0.150114)
			(end 0.299974 0.150114)
			(stroke
				(width 0.1)
				(type default)
			)
			(layer "B.Fab")
		)
		(fp_line
			(start 0.299974 0.150114)
			(end 0.299974 -0.150114)
			(stroke
				(width 0.1)
				(type default)
			)
			(layer "B.Fab")
		)
		(fp_line
			(start -0.299974 -0.150114)
			(end -0.299974 0.150114)
			(stroke
				(width 0.1)
				(type default)
			)
			(layer "B.Fab")
		)
		(fp_line
			(start 0.299974 -0.150114)
			(end -0.299974 -0.150114)
			(stroke
				(width 0.1)
				(type default)
			)
			(layer "B.Fab")
		)
		(pad "1" smd rect
			(at 0.2667 0 90)
			(size 0.3048 0.381)
			(layers "B.Cu" "B.Mask" "B.Paste")
			(net "P0V9_CPU0_RT2_2A")
		)
		(pad "2" smd rect
			(at -0.2667 0 90)
			(size 0.3048 0.381)
			(layers "B.Cu" "B.Mask" "B.Paste")
			(net "GND")
		)
	)
	(footprint ""
		(layer "B.Cu")
		(at 197.98665 -193.996564)
		(property "Reference" "C176"
			(at 0 0 0)
			(layer "B.SilkS")
			(hide yes)
			(effects
				(font
					(size 1.27 1.27)
				)
				(justify mirror)
			)
		)
		(property "Value" ""
			(at 0 0 0)
			(layer "B.Fab")
			(effects
				(font
					(size 1.27 1.27)
				)
				(justify mirror)
			)
		)
		(duplicate_pad_numbers_are_jumpers no)
		(fp_line
			(start -0.7874 -0.4064)
			(end -0.7874 0.4064)
			(stroke
				(width 0.1524)
				(type default)
			)
			(layer "B.SilkS")
		)
		(fp_line
			(start -0.7874 0.4064)
			(end 0.7874 0.4064)
			(stroke
				(width 0.1524)
				(type default)
			)
			(layer "B.SilkS")
		)
		(fp_line
			(start 0.7874 -0.4064)
			(end -0.7874 -0.4064)
			(stroke
				(width 0.1524)
				(type default)
			)
			(layer "B.SilkS")
		)
		(fp_line
			(start 0.7874 0.4064)
			(end 0.7874 -0.4064)
			(stroke
				(width 0.1524)
				(type default)
			)
			(layer "B.SilkS")
		)
		(fp_line
			(start -0.67945 -0.3048)
			(end -0.67945 0.3048)
			(stroke
				(width 0.1)
				(type default)
			)
			(layer "B.Fab")
		)
		(fp_line
			(start -0.67945 0.3048)
			(end -0.120396 0.3048)
			(stroke
				(width 0.1)
				(type default)
			)
			(layer "B.Fab")
		)
		(fp_line
			(start -0.12065 -0.3048)
			(end -0.67945 -0.3048)
			(stroke
				(width 0.1)
				(type default)
			)
			(layer "B.Fab")
		)
		(fp_line
			(start -0.12065 -0.2794)
			(end -0.12065 -0.3048)
			(stroke
				(width 0.1)
				(type default)
			)
			(layer "B.Fab")
		)
		(fp_line
			(start -0.120396 0.2794)
			(end 0.12065 0.2794)
			(stroke
				(width 0.1)
				(type default)
			)
			(layer "B.Fab")
		)
		(fp_line
			(start -0.120396 0.3048)
			(end -0.120396 0.2794)
			(stroke
				(width 0.1)
				(type default)
			)
			(layer "B.Fab")
		)
		(fp_line
			(start 0.12065 -0.305054)
			(end 0.12065 -0.2794)
			(stroke
				(width 0.1)
				(type default)
			)
			(layer "B.Fab")
		)
		(fp_line
			(start 0.12065 -0.2794)
			(end -0.12065 -0.2794)
			(stroke
				(width 0.1)
				(type default)
			)
			(layer "B.Fab")
		)
		(fp_line
			(start 0.12065 0.2794)
			(end 0.12065 0.3048)
			(stroke
				(width 0.1)
				(type default)
			)
			(layer "B.Fab")
		)
		(fp_line
			(start 0.12065 0.3048)
			(end 0.67945 0.3048)
			(stroke
				(width 0.1)
				(type default)
			)
			(layer "B.Fab")
		)
		(fp_line
			(start 0.67945 -0.305054)
			(end 0.12065 -0.305054)
			(stroke
				(width 0.1)
				(type default)
			)
			(layer "B.Fab")
		)
		(fp_line
			(start 0.67945 0.3048)
			(end 0.67945 -0.305054)
			(stroke
				(width 0.1)
				(type default)
			)
			(layer "B.Fab")
		)
		(pad "1" smd circle
			(at 0.40005 0 180)
			(size 0 0)
			(layers "B.Cu" "B.Mask" "B.Paste")
			(net "P3V3_AUX")
		)
		(pad "2" smd circle
			(at -0.40005 0 180)
			(size 0 0)
			(layers "B.Cu" "B.Mask" "B.Paste")
			(net "GND")
		)
	)
)
